# S9S_MB_2U (Grand Teton) — schematic netlist excerpt (pin names and nets, part order shuffled) for the footprints in the layout excerpt that follows; sources: Cadence DE-HDL packaged netlist, KiCad conversion of 03242023_DA0F0TMBIJ0_F0T_Motherboard_J_brd_V01_OCP.brd

J114  PICOPROBE_BXA  DELTA-L 4.0 EMPTY  pkg TRIANG_LAUNCH_3PXB  page 308
  \1_p\  = DELTA_L_85_5INCH_IN5_DP
  \2_n\  = DELTA_L_85_5INCH_IN5_DN
  \3_g\  = DELTA_L_GND_1

(kicad_pcb
	(version 20260206)
	(generator "pcbnew")
	(generator_version "10.0")
	(general
		(thickness 1.6)
		(legacy_teardrops no)
	)
	(paper "A4")
	(title_block
		(title "03242023_DA0F0TMBIJ0_F0T_Motherboard_J_brd_V01_OCP.brd")
		(comment 1 "Grand Teton / footprints 4484-4484 of 6105")
	)
	(layers
		(0 "F.Cu" signal "TOP")
		(4 "In1.Cu" signal "GND")
		(6 "In2.Cu" signal "IN1")
		(8 "In3.Cu" signal "GND1")
		(10 "In4.Cu" signal "IN2")
		(12 "In5.Cu" signal "GND2")
		(14 "In6.Cu" signal "IN3")
		(16 "In7.Cu" signal "GND3")
		(18 "In8.Cu" signal "VCC")
		(20 "In9.Cu" signal "VCC1")
		(22 "In10.Cu" signal "GND4")
		(24 "In11.Cu" signal "IN4")
		(26 "In12.Cu" signal "GND5")
		(28 "In13.Cu" signal "IN5")
		(30 "In14.Cu" signal "GND6")
		(32 "In15.Cu" signal "IN6")
		(34 "In16.Cu" signal "GND7")
		(2 "B.Cu" signal "BOTTOM")
		(9 "F.Adhes" user "F.Adhesive")
		(11 "B.Adhes" user "B.Adhesive")
		(13 "F.Paste" user "Package Geometry/Pastemask Top")
		(15 "B.Paste" user "Package Geometry/Pastemask Bottom")
		(5 "F.SilkS" user "Ref Des/Silkscreen Top")
		(7 "B.SilkS" user "Ref Des/Silkscreen Bottom")
		(1 "F.Mask" user "Board Geometry/Soldermask Top")
		(3 "B.Mask" user "Board Geometry/Soldermask Bottom")
		(17 "Dwgs.User" user "User.Drawings")
		(19 "Cmts.User" user "User.Comments")
		(21 "Eco1.User" user "User.Eco1")
		(23 "Eco2.User" user "User.Eco2")
		(25 "Edge.Cuts" user "Board Geometry/Outline")
		(27 "Margin" user)
		(31 "F.CrtYd" user "Package Geometry/Place Bound Top")
		(29 "B.CrtYd" user "Package Geometry/Place Bound Bottom")
		(35 "F.Fab" user "Ref Des/Assembly Top")
		(33 "B.Fab" user "Ref Des/Assembly Bottom")
	)
	(footprint ""
		(layer "B.Cu")
		(at 339.298534 8.003794 180)
		(property "Reference" "J114"
			(at 4.172204 -1.648206 270)
			(unlocked yes)
			(layer "B.SilkS")
			(effects
				(font
					(size 0.7874 0.5842)
					(thickness 0.1524)
				)
				(justify left mirror)
			)
		)
		(property "Value" ""
			(at 0 0 0)
			(layer "B.Fab")
			(effects
				(font
					(size 1.27 1.27)
				)
				(justify mirror)
			)
		)
		(duplicate_pad_numbers_are_jumpers no)
		(fp_line
			(start 1.2192 2.1082)
			(end 1.2192 -2.1082)
			(stroke
				(width 0.1524)
				(type default)
			)
			(layer "B.SilkS")
		)
		(fp_line
			(start 1.2192 -2.1082)
			(end -1.2192 -2.1082)
			(stroke
				(width 0.1524)
				(type default)
			)
			(layer "B.SilkS")
		)
		(fp_line
			(start -1.2192 2.1082)
			(end 1.2192 2.1082)
			(stroke
				(width 0.1524)
				(type default)
			)
			(layer "B.SilkS")
		)
		(fp_line
			(start -1.2192 -2.1082)
			(end -1.2192 2.1082)
			(stroke
				(width 0.1524)
				(type default)
			)
			(layer "B.SilkS")
		)
		(pad "" np_thru_hole circle
			(at -3.4671 -1.27 90)
			(size 1.0414 1.0414)
			(drill 1.0414)
			(layers "*.Cu" "*.Mask")
			(clearance 0.381)
			(thermal_gap 0.381)
		)
		(pad "" np_thru_hole circle
			(at -3.4671 1.27 90)
			(size 1.0414 1.0414)
			(drill 1.0414)
			(layers "*.Cu" "*.Mask")
			(clearance 0.381)
			(thermal_gap 0.381)
		)
		(pad "" np_thru_hole circle
			(at 2.8829 -1.27 90)
			(size 1.0414 1.0414)
			(drill 1.0414)
			(layers "*.Cu" "*.Mask")
			(clearance 0.381)
			(thermal_gap 0.381)
		)
		(pad "" np_thru_hole circle
			(at 2.8829 1.27 90)
			(size 1.0414 1.0414)
			(drill 1.0414)
			(layers "*.Cu" "*.Mask")
			(clearance 0.381)
			(thermal_gap 0.381)
		)
		(pad "1" smd rect
			(at -0.8255 -0.249936 90)
			(size 0.3048 0.508)
			(layers "B.Cu" "B.Mask" "B.Paste")
			(net "DELTA_L_85_5INCH_IN5_DP")
		)
		(pad "2" smd rect
			(at -0.8255 0.249936 90)
			(size 0.3048 0.508)
			(layers "B.Cu" "B.Mask" "B.Paste")
			(net "DELTA_L_85_5INCH_IN5_DN")
		)
		(pad "3" smd circle
			(at 0 0)
			(size 0 0)
			(layers "B.Cu" "B.Mask" "B.Paste")
			(net "DELTA_L_GND_1")
		)
		(zone
			(layers "F.Cu" "B.Cu" "In1.Cu" "In2.Cu" "In3.Cu" "In4.Cu" "In5.Cu" "In6.Cu"
				"In7.Cu" "In8.Cu" "In9.Cu" "In10.Cu" "In11.Cu" "In12.Cu" "In13.Cu" "In14.Cu"
				"In15.Cu" "In16.Cu"
			)
			(hatch none 0.5)
			(connect_pads
				(clearance 0)
			)
			(min_thickness 0.25)
			(keepout
				(tracks not_allowed)
				(vias allowed)
				(pads allowed)
				(copperpour not_allowed)
				(footprints allowed)
			)
			(placement
				(enabled no)
				(sheetname "")
			)
			(fill
				(thermal_gap 0.5)
				(thermal_bridge_width 0.5)
				(island_removal_mode 0)
			)
			(polygon
				(pts
					(arc
						(start 337.342734 6.733794)
						(mid 335.488534 6.733794)
						(end 337.342734 6.733794)
					)
				)
			)
		)
		(zone
			(layers "F.Cu" "B.Cu" "In1.Cu" "In2.Cu" "In3.Cu" "In4.Cu" "In5.Cu" "In6.Cu"
				"In7.Cu" "In8.Cu" "In9.Cu" "In10.Cu" "In11.Cu" "In12.Cu" "In13.Cu" "In14.Cu"
				"In15.Cu" "In16.Cu"
			)
			(hatch none 0.5)
			(connect_pads
				(clearance 0)
			)
			(min_thickness 0.25)
			(keepout
				(tracks not_allowed)
				(vias allowed)
				(pads allowed)
				(copperpour not_allowed)
				(footprints allowed)
			)
			(placement
				(enabled no)
				(sheetname "")
			)
			(fill
				(thermal_gap 0.5)
				(thermal_bridge_width 0.5)
				(island_removal_mode 0)
			)
			(polygon
				(pts
					(arc
						(start 337.342734 9.273794)
						(mid 335.488534 9.273794)
						(end 337.342734 9.273794)
					)
				)
			)
		)
		(zone
			(layers "F.Cu" "B.Cu" "In1.Cu" "In2.Cu" "In3.Cu" "In4.Cu" "In5.Cu" "In6.Cu"
				"In7.Cu" "In8.Cu" "In9.Cu" "In10.Cu" "In11.Cu" "In12.Cu" "In13.Cu" "In14.Cu"
				"In15.Cu" "In16.Cu"
			)
			(hatch none 0.5)
			(connect_pads
				(clearance 0)
			)
			(min_thickness 0.25)
			(keepout
				(tracks not_allowed)
				(vias allowed)
				(pads allowed)
				(copperpour not_allowed)
				(footprints allowed)
			)
			(placement
				(enabled no)
				(sheetname "")
			)
			(fill
				(thermal_gap 0.5)
				(thermal_bridge_width 0.5)
				(island_removal_mode 0)
			)
			(polygon
				(pts
					(arc
						(start 343.692734 6.733794)
						(mid 341.838534 6.733794)
						(end 343.692734 6.733794)
					)
				)
			)
		)
		(zone
			(layers "F.Cu" "B.Cu" "In1.Cu" "In2.Cu" "In3.Cu" "In4.Cu" "In5.Cu" "In6.Cu"
				"In7.Cu" "In8.Cu" "In9.Cu" "In10.Cu" "In11.Cu" "In12.Cu" "In13.Cu" "In14.Cu"
				"In15.Cu" "In16.Cu"
			)
			(hatch none 0.5)
			(connect_pads
				(clearance 0)
			)
			(min_thickness 0.25)
			(keepout
				(tracks not_allowed)
				(vias allowed)
				(pads allowed)
				(copperpour not_allowed)
				(footprints allowed)
			)
			(placement
				(enabled no)
				(sheetname "")
			)
			(fill
				(thermal_gap 0.5)
				(thermal_bridge_width 0.5)
				(island_removal_mode 0)
			)
			(polygon
				(pts
					(arc
						(start 343.692734 9.273794)
						(mid 341.838534 9.273794)
						(end 343.692734 9.273794)
					)
				)
			)
		)
		(zone
			(layer "B.Cu")
			(hatch none 0.5)
			(connect_pads
				(clearance 0)
			)
			(min_thickness 0.25)
			(keepout
				(tracks not_allowed)
				(vias allowed)
				(pads allowed)
				(copperpour not_allowed)
				(footprints allowed)
			)
			(placement
				(enabled no)
				(sheetname "")
			)
			(fill
				(thermal_gap 0.5)
				(thermal_bridge_width 0.5)
				(island_removal_mode 0)
			)
			(polygon
				(pts
					(xy 340.416134 8.552434) (xy 340.416134 8.45693) (xy 339.819234 8.45693) (xy 339.819234 8.05053)
					(xy 340.416134 8.05053) (xy 340.416134 7.957058) (xy 339.819234 7.957058) (xy 339.819234 7.550658)
					(xy 340.416134 7.550658) (xy 340.416134 7.455154) (xy 339.717634 7.455154) (xy 339.717634 8.552434)
				)
			)
		)
	)
)
